(kicad_pcb
	(version 20260206)
	(generator "pcbnew")
	(generator_version "10.0")
	(general
		(thickness 1.6)
		(legacy_teardrops no)
	)
	(paper "A4")
	(title_block
		(title "peb — Lightning_PEB_BRD.brd")
		(comment 1 "Lightning (Wiwynn / Facebook NVMe JBOF) / footprints 2357-2363 of 2563")
	)
	(layers
		(0 "F.Cu" signal "TOP")
		(4 "In1.Cu" signal "L2GND")
		(6 "In2.Cu" signal "L3")
		(8 "In3.Cu" signal "L4VCC")
		(10 "In4.Cu" signal "L5VCC")
		(12 "In5.Cu" signal "L6")
		(14 "In6.Cu" signal "L7GND")
		(2 "B.Cu" signal "BOTTOM")
		(9 "F.Adhes" user "F.Adhesive")
		(11 "B.Adhes" user "B.Adhesive")
		(13 "F.Paste" user "Package Geometry/Pastemask Top")
		(15 "B.Paste" user "Package Geometry/Pastemask Bottom")
		(5 "F.SilkS" user "Ref Des/Silkscreen Top")
		(7 "B.SilkS" user "Ref Des/Silkscreen Bottom")
		(1 "F.Mask" user "Board Geometry/Soldermask Top")
		(3 "B.Mask" user "Board Geometry/Soldermask Bottom")
		(17 "Dwgs.User" user "User.Drawings")
		(19 "Cmts.User" user "User.Comments")
		(21 "Eco1.User" user "User.Eco1")
		(23 "Eco2.User" user "User.Eco2")
		(25 "Edge.Cuts" user "Board Geometry/Outline")
		(27 "Margin" user)
		(31 "F.CrtYd" user "Package Geometry/Place Bound Top")
		(29 "B.CrtYd" user "Package Geometry/Place Bound Bottom")
		(35 "F.Fab" user "Ref Des/Assembly Top")
		(33 "B.Fab" user "Ref Des/Assembly Bottom")
	)
	(footprint ""
		(layer "B.Cu")
		(at 344.17 -71.501 180)
		(property "Reference" "PR2"
			(at 0 0 0)
			(layer "B.SilkS")
			(hide yes)
			(effects
				(font
					(size 1.27 1.27)
				)
				(justify mirror)
			)
		)
		(property "Value" "121KR2F-L-GP"
			(at -0.064008 -3.993896 180)
			(unlocked yes)
			(layer "B.Fab")
			(hide yes)
			(effects
				(font
					(size 1.016 1.016)
					(thickness 0.1524)
				)
				(justify mirror)
			)
		)
		(property "Device Type" "R402H16"
			(at -0.064008 -5.517896 180)
			(unlocked yes)
			(layer "B.Fab")
			(hide yes)
			(effects
				(font
					(size 1.016 1.016)
					(thickness 0.1524)
				)
				(justify mirror)
			)
		)
		(duplicate_pad_numbers_are_jumpers no)
		(fp_line
			(start 0.508 -0.9398)
			(end 0.508 0.9398)
			(stroke
				(width 0.1524)
				(type default)
			)
			(layer "B.SilkS")
		)
		(fp_line
			(start -0.508 -0.9398)
			(end 0.508 -0.9398)
			(stroke
				(width 0.1524)
				(type default)
			)
			(layer "B.SilkS")
		)
		(fp_rect
			(start 0.508 0.9398)
			(end -0.508 -0.9398)
			(stroke
				(width 0)
				(type default)
			)
			(fill no)
			(layer "B.CrtYd")
		)
		(fp_rect
			(start 0.508 0.9398)
			(end -0.508 -0.9398)
			(stroke
				(width 0)
				(type default)
			)
			(fill no)
			(layer "B.Fab")
		)
		(pad "1" smd custom
			(at 0 -0.4445)
			(size 0.1397 0.1397)
			(layers "B.Cu" "B.Mask" "B.Paste")
			(net "P0V9_E_TRIP")
			(options
				(clearance outline)
				(anchor circle)
			)
			(primitives
				(gr_poly
					(pts
						(arc
							(start -0.1778 0.2794)
							(mid -0.249642 0.249642)
							(end -0.2794 0.1778)
						)
						(arc
							(start -0.2794 -0.1778)
							(mid -0.249642 -0.249642)
							(end -0.1778 -0.2794)
						)
						(arc
							(start 0.1778 -0.2794)
							(mid 0.249642 -0.249642)
							(end 0.2794 -0.1778)
						)
						(arc
							(start 0.2794 0.1778)
							(mid 0.249642 0.249642)
							(end 0.1778 0.2794)
						)
					)
					(width 0)
					(fill yes)
				)
			)
		)
		(pad "2" smd custom
			(at 0 0.4445)
			(size 0.1397 0.1397)
			(layers "B.Cu" "B.Mask" "B.Paste")
			(net "AGND_P0V9_E")
			(options
				(clearance outline)
				(anchor circle)
			)
			(primitives
				(gr_poly
					(pts
						(arc
							(start -0.1778 0.2794)
							(mid -0.249642 0.249642)
							(end -0.2794 0.1778)
						)
						(arc
							(start -0.2794 -0.1778)
							(mid -0.249642 -0.249642)
							(end -0.1778 -0.2794)
						)
						(arc
							(start 0.1778 -0.2794)
							(mid 0.249642 -0.249642)
							(end 0.2794 -0.1778)
						)
						(arc
							(start 0.2794 0.1778)
							(mid 0.249642 0.249642)
							(end 0.1778 0.2794)
						)
					)
					(width 0)
					(fill yes)
				)
			)
		)
	)
	(footprint ""
		(layer "B.Cu")
		(at 267.0683 -8.85571 180)
		(property "Reference" "R2967"
			(at 0 0 0)
			(layer "B.SilkS")
			(hide yes)
			(effects
				(font
					(size 1.27 1.27)
				)
				(justify mirror)
			)
		)
		(property "Value" "0R2J-2-GP"
			(at -0.064008 -3.993896 180)
			(unlocked yes)
			(layer "B.Fab")
			(hide yes)
			(effects
				(font
					(size 1.016 1.016)
					(thickness 0.1524)
				)
				(justify mirror)
			)
		)
		(property "Device Type" "R402H16"
			(at -0.064008 -5.517896 180)
			(unlocked yes)
			(layer "B.Fab")
			(hide yes)
			(effects
				(font
					(size 1.016 1.016)
					(thickness 0.1524)
				)
				(justify mirror)
			)
		)
		(duplicate_pad_numbers_are_jumpers no)
		(fp_line
			(start 0.508 -0.9398)
			(end 0.508 0.9398)
			(stroke
				(width 0.1524)
				(type default)
			)
			(layer "B.SilkS")
		)
		(fp_line
			(start -0.508 -0.9398)
			(end 0.508 -0.9398)
			(stroke
				(width 0.1524)
				(type default)
			)
			(layer "B.SilkS")
		)
		(fp_rect
			(start 0.508 0.9398)
			(end -0.508 -0.9398)
			(stroke
				(width 0)
				(type default)
			)
			(fill no)
			(layer "B.CrtYd")
		)
		(fp_rect
			(start 0.508 0.9398)
			(end -0.508 -0.9398)
			(stroke
				(width 0)
				(type default)
			)
			(fill no)
			(layer "B.Fab")
		)
		(pad "1" smd custom
			(at 0 -0.4445)
			(size 0.1397 0.1397)
			(layers "B.Cu" "B.Mask" "B.Paste")
			(net "HOST8_RST_N")
			(options
				(clearance outline)
				(anchor circle)
			)
			(primitives
				(gr_poly
					(pts
						(arc
							(start -0.1778 0.2794)
							(mid -0.249642 0.249642)
							(end -0.2794 0.1778)
						)
						(arc
							(start -0.2794 -0.1778)
							(mid -0.249642 -0.249642)
							(end -0.1778 -0.2794)
						)
						(arc
							(start 0.1778 -0.2794)
							(mid 0.249642 -0.249642)
							(end 0.2794 -0.1778)
						)
						(arc
							(start 0.2794 0.1778)
							(mid 0.249642 0.249642)
							(end 0.1778 0.2794)
						)
					)
					(width 0)
					(fill yes)
				)
			)
		)
		(pad "2" smd custom
			(at 0 0.4445)
			(size 0.1397 0.1397)
			(layers "B.Cu" "B.Mask" "B.Paste")
			(net "HOST8_RST_N_C")
			(options
				(clearance outline)
				(anchor circle)
			)
			(primitives
				(gr_poly
					(pts
						(arc
							(start -0.1778 0.2794)
							(mid -0.249642 0.249642)
							(end -0.2794 0.1778)
						)
						(arc
							(start -0.2794 -0.1778)
							(mid -0.249642 -0.249642)
							(end -0.1778 -0.2794)
						)
						(arc
							(start 0.1778 -0.2794)
							(mid 0.249642 -0.249642)
							(end 0.2794 -0.1778)
						)
						(arc
							(start 0.2794 0.1778)
							(mid 0.249642 0.249642)
							(end 0.1778 0.2794)
						)
					)
					(width 0)
					(fill yes)
				)
			)
		)
	)
	(footprint ""
		(layer "B.Cu")
		(at 39.842948 -127.002794 180)
		(property "Reference" "C216"
			(at 0 0 0)
			(layer "B.SilkS")
			(hide yes)
			(effects
				(font
					(size 1.27 1.27)
				)
				(justify mirror)
			)
		)
		(property "Value" "SC1U10V2KX-4-GP"
			(at -1.1811 -2.7051 180)
			(unlocked yes)
			(layer "B.Fab")
			(hide yes)
			(effects
				(font
					(size 1.016 1.016)
					(thickness 0.1524)
				)
				(justify mirror)
			)
		)
		(property "Device Type" "C402H22"
			(at -1.1811 -4.2291 180)
			(unlocked yes)
			(layer "B.Fab")
			(hide yes)
			(effects
				(font
					(size 1.016 1.016)
					(thickness 0.1524)
				)
				(justify mirror)
			)
		)
		(duplicate_pad_numbers_are_jumpers no)
		(fp_rect
			(start 0.4318 0.9525)
			(end -0.4318 -0.9525)
			(stroke
				(width 0)
				(type default)
			)
			(fill no)
			(layer "B.CrtYd")
		)
		(fp_rect
			(start 0.4318 0.9525)
			(end -0.4318 -0.9525)
			(stroke
				(width 0)
				(type default)
			)
			(fill no)
			(layer "B.Fab")
		)
		(pad "1" smd custom
			(at 0 -0.4445)
			(size 0.1524 0.1524)
			(layers "B.Cu" "B.Mask" "B.Paste")
			(net "P3V3_STBY")
			(options
				(clearance outline)
				(anchor circle)
			)
			(primitives
				(gr_poly
					(pts
						(arc
							(start 0.3048 0.2032)
							(mid 0.275042 0.275042)
							(end 0.2032 0.3048)
						)
						(arc
							(start -0.2032 0.3048)
							(mid -0.275042 0.275042)
							(end -0.3048 0.2032)
						)
						(arc
							(start -0.3048 -0.2032)
							(mid -0.275042 -0.275042)
							(end -0.2032 -0.3048)
						)
						(arc
							(start 0.2032 -0.3048)
							(mid 0.275042 -0.275042)
							(end 0.3048 -0.2032)
						)
					)
					(width 0)
					(fill yes)
				)
			)
		)
		(pad "2" smd custom
			(at 0 0.4445)
			(size 0.1524 0.1524)
			(layers "B.Cu" "B.Mask" "B.Paste")
			(net "GND")
			(options
				(clearance outline)
				(anchor circle)
			)
			(primitives
				(gr_poly
					(pts
						(arc
							(start 0.3048 0.2032)
							(mid 0.275042 0.275042)
							(end 0.2032 0.3048)
						)
						(arc
							(start -0.2032 0.3048)
							(mid -0.275042 0.275042)
							(end -0.3048 0.2032)
						)
						(arc
							(start -0.3048 -0.2032)
							(mid -0.275042 -0.275042)
							(end -0.2032 -0.3048)
						)
						(arc
							(start 0.2032 -0.3048)
							(mid 0.275042 -0.275042)
							(end 0.3048 -0.2032)
						)
					)
					(width 0)
					(fill yes)
				)
			)
		)
	)
	(footprint ""
		(layer "B.Cu")
		(at 59.218322 -123.425966 90)
		(property "Reference" "R323"
			(at 0 0 90)
			(layer "B.SilkS")
			(hide yes)
			(effects
				(font
					(size 1.27 1.27)
				)
				(justify mirror)
			)
		)
		(property "Value" "4K7R2F-GP"
			(at -0.064008 -3.993896 90)
			(unlocked yes)
			(layer "B.Fab")
			(hide yes)
			(effects
				(font
					(size 1.016 1.016)
					(thickness 0.1524)
				)
				(justify mirror)
			)
		)
		(property "Device Type" "R402H16"
			(at -0.064008 -5.517896 90)
			(unlocked yes)
			(layer "B.Fab")
			(hide yes)
			(effects
				(font
					(size 1.016 1.016)
					(thickness 0.1524)
				)
				(justify mirror)
			)
		)
		(duplicate_pad_numbers_are_jumpers no)
		(fp_line
			(start 0.508 -0.9398)
			(end 0.508 0.9398)
			(stroke
				(width 0.1524)
				(type default)
			)
			(layer "B.SilkS")
		)
		(fp_line
			(start -0.508 -0.9398)
			(end 0.508 -0.9398)
			(stroke
				(width 0.1524)
				(type default)
			)
			(layer "B.SilkS")
		)
		(fp_rect
			(start 0.508 0.9398)
			(end -0.508 -0.9398)
			(stroke
				(width 0)
				(type default)
			)
			(fill no)
			(layer "B.CrtYd")
		)
		(fp_rect
			(start 0.508 0.9398)
			(end -0.508 -0.9398)
			(stroke
				(width 0)
				(type default)
			)
			(fill no)
			(layer "B.Fab")
		)
		(pad "1" smd custom
			(at 0 -0.4445 270)
			(size 0.1397 0.1397)
			(layers "B.Cu" "B.Mask" "B.Paste")
			(net "BMC_I2C8_CLKBUF1_SDA")
			(options
				(clearance outline)
				(anchor circle)
			)
			(primitives
				(gr_poly
					(pts
						(arc
							(start -0.1778 0.2794)
							(mid -0.249642 0.249642)
							(end -0.2794 0.1778)
						)
						(arc
							(start -0.2794 -0.1778)
							(mid -0.249642 -0.249642)
							(end -0.1778 -0.2794)
						)
						(arc
							(start 0.1778 -0.2794)
							(mid 0.249642 -0.249642)
							(end 0.2794 -0.1778)
						)
						(arc
							(start 0.2794 0.1778)
							(mid 0.249642 0.249642)
							(end 0.1778 0.2794)
						)
					)
					(width 0)
					(fill yes)
				)
			)
		)
		(pad "2" smd custom
			(at 0 0.4445 270)
			(size 0.1397 0.1397)
			(layers "B.Cu" "B.Mask" "B.Paste")
			(net "P3V3_STBY")
			(options
				(clearance outline)
				(anchor circle)
			)
			(primitives
				(gr_poly
					(pts
						(arc
							(start -0.1778 0.2794)
							(mid -0.249642 0.249642)
							(end -0.2794 0.1778)
						)
						(arc
							(start -0.2794 -0.1778)
							(mid -0.249642 -0.249642)
							(end -0.1778 -0.2794)
						)
						(arc
							(start 0.1778 -0.2794)
							(mid 0.249642 -0.249642)
							(end 0.2794 -0.1778)
						)
						(arc
							(start 0.2794 0.1778)
							(mid 0.249642 0.249642)
							(end 0.1778 0.2794)
						)
					)
					(width 0)
					(fill yes)
				)
			)
		)
	)
	(footprint ""
		(layer "B.Cu")
		(at 26.289 -116.713)
		(property "Reference" "R259"
			(at 0 0 0)
			(layer "B.SilkS")
			(hide yes)
			(effects
				(font
					(size 1.27 1.27)
				)
				(justify mirror)
			)
		)
		(property "Value" "100KR2F-L1-GP"
			(at -0.064008 -3.993896 0)
			(unlocked yes)
			(layer "B.Fab")
			(hide yes)
			(effects
				(font
					(size 1.016 1.016)
					(thickness 0.1524)
				)
				(justify mirror)
			)
		)
		(property "Device Type" "R402H16"
			(at -0.064008 -5.517896 0)
			(unlocked yes)
			(layer "B.Fab")
			(hide yes)
			(effects
				(font
					(size 1.016 1.016)
					(thickness 0.1524)
				)
				(justify mirror)
			)
		)
		(duplicate_pad_numbers_are_jumpers no)
		(fp_line
			(start -0.508 -0.9398)
			(end 0.508 -0.9398)
			(stroke
				(width 0.1524)
				(type default)
			)
			(layer "B.SilkS")
		)
		(fp_line
			(start 0.508 -0.9398)
			(end 0.508 0.9398)
			(stroke
				(width 0.1524)
				(type default)
			)
			(layer "B.SilkS")
		)
		(fp_rect
			(start 0.508 0.9398)
			(end -0.508 -0.9398)
			(stroke
				(width 0)
				(type default)
			)
			(fill no)
			(layer "B.CrtYd")
		)
		(fp_rect
			(start 0.508 0.9398)
			(end -0.508 -0.9398)
			(stroke
				(width 0)
				(type default)
			)
			(fill no)
			(layer "B.Fab")
		)
		(pad "1" smd custom
			(at 0 -0.4445 180)
			(size 0.1397 0.1397)
			(layers "B.Cu" "B.Mask" "B.Paste")
			(net "TP_IRQ_CPU_SERIAL")
			(options
				(clearance outline)
				(anchor circle)
			)
			(primitives
				(gr_poly
					(pts
						(arc
							(start -0.1778 0.2794)
							(mid -0.249642 0.249642)
							(end -0.2794 0.1778)
						)
						(arc
							(start -0.2794 -0.1778)
							(mid -0.249642 -0.249642)
							(end -0.1778 -0.2794)
						)
						(arc
							(start 0.1778 -0.2794)
							(mid 0.249642 -0.249642)
							(end 0.2794 -0.1778)
						)
						(arc
							(start 0.2794 0.1778)
							(mid 0.249642 0.249642)
							(end 0.1778 0.2794)
						)
					)
					(width 0)
					(fill yes)
				)
			)
		)
		(pad "2" smd custom
			(at 0 0.4445 180)
			(size 0.1397 0.1397)
			(layers "B.Cu" "B.Mask" "B.Paste")
			(net "GND")
			(options
				(clearance outline)
				(anchor circle)
			)
			(primitives
				(gr_poly
					(pts
						(arc
							(start -0.1778 0.2794)
							(mid -0.249642 0.249642)
							(end -0.2794 0.1778)
						)
						(arc
							(start -0.2794 -0.1778)
							(mid -0.249642 -0.249642)
							(end -0.1778 -0.2794)
						)
						(arc
							(start 0.1778 -0.2794)
							(mid 0.249642 -0.249642)
							(end 0.2794 -0.1778)
						)
						(arc
							(start 0.2794 0.1778)
							(mid 0.249642 0.249642)
							(end 0.1778 0.2794)
						)
					)
					(width 0)
					(fill yes)
				)
			)
		)
	)
	(footprint ""
		(layer "B.Cu")
		(at 241.6048 -59.0042 -90)
		(property "Reference" "C509"
			(at 0 0 90)
			(layer "B.SilkS")
			(hide yes)
			(effects
				(font
					(size 1.27 1.27)
				)
				(justify mirror)
			)
		)
		(property "Value" "SCD1U16V1KX-1-GP"
			(at 2.8321 -1.7399 270)
			(unlocked yes)
			(layer "B.Fab")
			(hide yes)
			(effects
				(font
					(size 1.016 1.016)
					(thickness 0.1524)
				)
				(justify mirror)
			)
		)
		(property "Device Type" "C0201H13"
			(at 2.8321 -3.2639 270)
			(unlocked yes)
			(layer "B.Fab")
			(hide yes)
			(effects
				(font
					(size 1.016 1.016)
					(thickness 0.1524)
				)
				(justify mirror)
			)
		)
		(duplicate_pad_numbers_are_jumpers no)
		(fp_rect
			(start 0.2794 0.6477)
			(end -0.2794 -0.6477)
			(stroke
				(width 0)
				(type default)
			)
			(fill no)
			(layer "B.CrtYd")
		)
		(fp_rect
			(start 0.2794 0.6477)
			(end -0.2794 -0.6477)
			(stroke
				(width 0)
				(type default)
			)
			(fill no)
			(layer "B.Fab")
		)
		(pad "1" smd custom
			(at 0 -0.2794 90)
			(size 0.0762 0.0762)
			(layers "B.Cu" "B.Mask" "B.Paste")
			(net "DUT_AVD_TX")
			(options
				(clearance outline)
				(anchor circle)
			)
			(primitives
				(gr_poly
					(pts
						(arc
							(start 0.1524 0.127)
							(mid 0.137521 0.162921)
							(end 0.1016 0.1778)
						)
						(arc
							(start -0.1016 0.1778)
							(mid -0.137521 0.162921)
							(end -0.1524 0.127)
						)
						(arc
							(start -0.1524 -0.127)
							(mid -0.137521 -0.162921)
							(end -0.1016 -0.1778)
						)
						(arc
							(start 0.1016 -0.1778)
							(mid 0.137521 -0.162921)
							(end 0.1524 -0.127)
						)
					)
					(width 0)
					(fill yes)
				)
			)
		)
		(pad "2" smd custom
			(at 0 0.2794 90)
			(size 0.0762 0.0762)
			(layers "B.Cu" "B.Mask" "B.Paste")
			(net "GND")
			(options
				(clearance outline)
				(anchor circle)
			)
			(primitives
				(gr_poly
					(pts
						(arc
							(start 0.1524 0.127)
							(mid 0.137521 0.162921)
							(end 0.1016 0.1778)
						)
						(arc
							(start -0.1016 0.1778)
							(mid -0.137521 0.162921)
							(end -0.1524 0.127)
						)
						(arc
							(start -0.1524 -0.127)
							(mid -0.137521 -0.162921)
							(end -0.1016 -0.1778)
						)
						(arc
							(start 0.1016 -0.1778)
							(mid 0.137521 -0.162921)
							(end 0.1524 -0.127)
						)
					)
					(width 0)
					(fill yes)
				)
			)
		)
	)
	(footprint ""
		(layer "B.Cu")
		(at 18.315432 -128.664208 -90)
		(property "Reference" "R565"
			(at 0 0 90)
			(layer "B.SilkS")
			(hide yes)
			(effects
				(font
					(size 1.27 1.27)
				)
				(justify mirror)
			)
		)
		(property "Value" "0R2J-2-GP"
			(at -0.064008 -3.993896 270)
			(unlocked yes)
			(layer "B.Fab")
			(hide yes)
			(effects
				(font
					(size 1.016 1.016)
					(thickness 0.1524)
				)
				(justify mirror)
			)
		)
		(property "Device Type" "R402H16"
			(at -0.064008 -5.517896 270)
			(unlocked yes)
			(layer "B.Fab")
			(hide yes)
			(effects
				(font
					(size 1.016 1.016)
					(thickness 0.1524)
				)
				(justify mirror)
			)
		)
		(duplicate_pad_numbers_are_jumpers no)
		(fp_line
			(start -0.508 -0.9398)
			(end 0.508 -0.9398)
			(stroke
				(width 0.1524)
				(type default)
			)
			(layer "B.SilkS")
		)
		(fp_line
			(start 0.508 -0.9398)
			(end 0.508 0.9398)
			(stroke
				(width 0.1524)
				(type default)
			)
			(layer "B.SilkS")
		)
		(fp_rect
			(start 0.508 0.9398)
			(end -0.508 -0.9398)
			(stroke
				(width 0)
				(type default)
			)
			(fill no)
			(layer "B.CrtYd")
		)
		(fp_rect
			(start 0.508 0.9398)
			(end -0.508 -0.9398)
			(stroke
				(width 0)
				(type default)
			)
			(fill no)
			(layer "B.Fab")
		)
		(pad "1" smd custom
			(at 0 -0.4445 90)
			(size 0.1397 0.1397)
			(layers "B.Cu" "B.Mask" "B.Paste")
			(net "PE1_PERST#")
			(options
				(clearance outline)
				(anchor circle)
			)
			(primitives
				(gr_poly
					(pts
						(arc
							(start -0.1778 0.2794)
							(mid -0.249642 0.249642)
							(end -0.2794 0.1778)
						)
						(arc
							(start -0.2794 -0.1778)
							(mid -0.249642 -0.249642)
							(end -0.1778 -0.2794)
						)
						(arc
							(start 0.1778 -0.2794)
							(mid 0.249642 -0.249642)
							(end 0.2794 -0.1778)
						)
						(arc
							(start 0.2794 0.1778)
							(mid 0.249642 0.249642)
							(end 0.1778 0.2794)
						)
					)
					(width 0)
					(fill yes)
				)
			)
		)
		(pad "2" smd custom
			(at 0 0.4445 90)
			(size 0.1397 0.1397)
			(layers "B.Cu" "B.Mask" "B.Paste")
			(net "PE1_PERST#_BMC")
			(options
				(clearance outline)
				(anchor circle)
			)
			(primitives
				(gr_poly
					(pts
						(arc
							(start -0.1778 0.2794)
							(mid -0.249642 0.249642)
							(end -0.2794 0.1778)
						)
						(arc
							(start -0.2794 -0.1778)
							(mid -0.249642 -0.249642)
							(end -0.1778 -0.2794)
						)
						(arc
							(start 0.1778 -0.2794)
							(mid 0.249642 -0.249642)
							(end 0.2794 -0.1778)
						)
						(arc
							(start 0.2794 0.1778)
							(mid 0.249642 0.249642)
							(end 0.1778 0.2794)
						)
					)
					(width 0)
					(fill yes)
				)
			)
		)
	)
)
